# S9S_MB_2U (Grand Teton) — schematic netlist excerpt (pin names and nets, part order shuffled) for the footprints in the layout excerpt that follows; sources: Cadence DE-HDL packaged netlist, KiCad conversion of 03242023_DA0F0TMBIJ0_F0T_Motherboard_J_brd_V01_OCP.brd

C487  Q_CAP  47UF 4V 20% X6S  pkg C0805  page 79 : A = PVCCINFAON_CPU1 ; B = GND
R1895  Q_RES  100 1% CHIP  pkg 0402LF  page 153 : A = OCP_SFF_PRSNTA_R_N ; B = GND
C33  Q_CAP  10UF 16V 10% X6S  pkg C0805  page 92 : A = P12V_S3_AUX_CPU0_NVDIMM ; B = GND

(kicad_pcb
	(version 20260206)
	(generator "pcbnew")
	(generator_version "10.0")
	(general
		(thickness 1.6)
		(legacy_teardrops no)
	)
	(paper "A4")
	(title_block
		(title "03242023_DA0F0TMBIJ0_F0T_Motherboard_J_brd_V01_OCP.brd")
		(comment 1 "Grand Teton / footprints 5881-5883 of 6105")
	)
	(layers
		(0 "F.Cu" signal "TOP")
		(4 "In1.Cu" signal "GND")
		(6 "In2.Cu" signal "IN1")
		(8 "In3.Cu" signal "GND1")
		(10 "In4.Cu" signal "IN2")
		(12 "In5.Cu" signal "GND2")
		(14 "In6.Cu" signal "IN3")
		(16 "In7.Cu" signal "GND3")
		(18 "In8.Cu" signal "VCC")
		(20 "In9.Cu" signal "VCC1")
		(22 "In10.Cu" signal "GND4")
		(24 "In11.Cu" signal "IN4")
		(26 "In12.Cu" signal "GND5")
		(28 "In13.Cu" signal "IN5")
		(30 "In14.Cu" signal "GND6")
		(32 "In15.Cu" signal "IN6")
		(34 "In16.Cu" signal "GND7")
		(2 "B.Cu" signal "BOTTOM")
		(9 "F.Adhes" user "F.Adhesive")
		(11 "B.Adhes" user "B.Adhesive")
		(13 "F.Paste" user "Package Geometry/Pastemask Top")
		(15 "B.Paste" user "Package Geometry/Pastemask Bottom")
		(5 "F.SilkS" user "Ref Des/Silkscreen Top")
		(7 "B.SilkS" user "Ref Des/Silkscreen Bottom")
		(1 "F.Mask" user "Board Geometry/Soldermask Top")
		(3 "B.Mask" user "Board Geometry/Soldermask Bottom")
		(17 "Dwgs.User" user "User.Drawings")
		(19 "Cmts.User" user "User.Comments")
		(21 "Eco1.User" user "User.Eco1")
		(23 "Eco2.User" user "User.Eco2")
		(25 "Edge.Cuts" user "Board Geometry/Outline")
		(27 "Margin" user)
		(31 "F.CrtYd" user "Package Geometry/Place Bound Top")
		(29 "B.CrtYd" user "Package Geometry/Place Bound Bottom")
		(35 "F.Fab" user "Ref Des/Assembly Top")
		(33 "B.Fab" user "Ref Des/Assembly Bottom")
	)
	(footprint ""
		(layer "B.Cu")
		(at 429.397414 -321.549776 -90)
		(property "Reference" "C33"
			(at 0 0 90)
			(layer "B.SilkS")
			(hide yes)
			(effects
				(font
					(size 1.27 1.27)
				)
				(justify mirror)
			)
		)
		(property "Value" ""
			(at 0 0 90)
			(layer "B.Fab")
			(effects
				(font
					(size 1.27 1.27)
				)
				(justify mirror)
			)
		)
		(duplicate_pad_numbers_are_jumpers no)
		(fp_line
			(start -1.524 0.762)
			(end 1.524 0.762)
			(stroke
				(width 0.1524)
				(type default)
			)
			(layer "B.SilkS")
		)
		(fp_line
			(start 1.524 0.762)
			(end 1.524 -0.762)
			(stroke
				(width 0.1524)
				(type default)
			)
			(layer "B.SilkS")
		)
		(fp_line
			(start -1.524 -0.762)
			(end -1.524 0.762)
			(stroke
				(width 0.1524)
				(type default)
			)
			(layer "B.SilkS")
		)
		(fp_line
			(start 1.524 -0.762)
			(end -1.524 -0.762)
			(stroke
				(width 0.1524)
				(type default)
			)
			(layer "B.SilkS")
		)
		(fp_line
			(start -1.1049 0.724916)
			(end -1.1049 -0.724916)
			(stroke
				(width 0.1)
				(type default)
			)
			(layer "B.Fab")
		)
		(fp_line
			(start 1.1049 0.724916)
			(end -1.1049 0.724916)
			(stroke
				(width 0.1)
				(type default)
			)
			(layer "B.Fab")
		)
		(fp_line
			(start -1.1049 -0.724916)
			(end 1.1049 -0.724916)
			(stroke
				(width 0.1)
				(type default)
			)
			(layer "B.Fab")
		)
		(fp_line
			(start 1.1049 -0.724916)
			(end 1.1049 0.724916)
			(stroke
				(width 0.1)
				(type default)
			)
			(layer "B.Fab")
		)
		(pad "1" smd rect
			(at 0.889 0 270)
			(size 1.016 1.27)
			(layers "B.Cu" "B.Mask" "B.Paste")
			(net "P12V_S3_AUX_CPU0_NVDIMM")
		)
		(pad "2" smd rect
			(at -0.889 0 270)
			(size 1.016 1.27)
			(layers "B.Cu" "B.Mask" "B.Paste")
			(net "GND")
		)
	)
	(footprint ""
		(layer "B.Cu")
		(at 121.582688 -210.194144 180)
		(property "Reference" "C487"
			(at 0 0 0)
			(layer "B.SilkS")
			(hide yes)
			(effects
				(font
					(size 1.27 1.27)
				)
				(justify mirror)
			)
		)
		(property "Value" ""
			(at 0 0 0)
			(layer "B.Fab")
			(effects
				(font
					(size 1.27 1.27)
				)
				(justify mirror)
			)
		)
		(duplicate_pad_numbers_are_jumpers no)
		(fp_line
			(start 1.524 0.762)
			(end 1.524 -0.762)
			(stroke
				(width 0.1524)
				(type default)
			)
			(layer "B.SilkS")
		)
		(fp_line
			(start 1.524 -0.762)
			(end -1.524 -0.762)
			(stroke
				(width 0.1524)
				(type default)
			)
			(layer "B.SilkS")
		)
		(fp_line
			(start -1.524 0.762)
			(end 1.524 0.762)
			(stroke
				(width 0.1524)
				(type default)
			)
			(layer "B.SilkS")
		)
		(fp_line
			(start -1.524 -0.762)
			(end -1.524 0.762)
			(stroke
				(width 0.1524)
				(type default)
			)
			(layer "B.SilkS")
		)
		(fp_line
			(start 1.1049 0.724916)
			(end -1.1049 0.724916)
			(stroke
				(width 0.1)
				(type default)
			)
			(layer "B.Fab")
		)
		(fp_line
			(start 1.1049 -0.724916)
			(end 1.1049 0.724916)
			(stroke
				(width 0.1)
				(type default)
			)
			(layer "B.Fab")
		)
		(fp_line
			(start -1.1049 0.724916)
			(end -1.1049 -0.724916)
			(stroke
				(width 0.1)
				(type default)
			)
			(layer "B.Fab")
		)
		(fp_line
			(start -1.1049 -0.724916)
			(end 1.1049 -0.724916)
			(stroke
				(width 0.1)
				(type default)
			)
			(layer "B.Fab")
		)
		(pad "1" smd rect
			(at 0.889 0 180)
			(size 1.016 1.27)
			(layers "B.Cu" "B.Mask" "B.Paste")
			(net "PVCCINFAON_CPU1")
		)
		(pad "2" smd rect
			(at -0.889 0 180)
			(size 1.016 1.27)
			(layers "B.Cu" "B.Mask" "B.Paste")
			(net "GND")
		)
	)
	(footprint ""
		(layer "B.Cu")
		(at 435.145942 -8.316976 -90)
		(property "Reference" "R1895"
			(at 0 0 90)
			(layer "B.SilkS")
			(hide yes)
			(effects
				(font
					(size 1.27 1.27)
				)
				(justify mirror)
			)
		)
		(property "Value" ""
			(at 0 0 90)
			(layer "B.Fab")
			(effects
				(font
					(size 1.27 1.27)
				)
				(justify mirror)
			)
		)
		(duplicate_pad_numbers_are_jumpers no)
		(fp_line
			(start -0.7874 0.4064)
			(end 0.7874 0.4064)
			(stroke
				(width 0.1524)
				(type default)
			)
			(layer "B.SilkS")
		)
		(fp_line
			(start 0.7874 0.4064)
			(end 0.7874 -0.4064)
			(stroke
				(width 0.1524)
				(type default)
			)
			(layer "B.SilkS")
		)
		(fp_line
			(start -0.7874 -0.4064)
			(end -0.7874 0.4064)
			(stroke
				(width 0.1524)
				(type default)
			)
			(layer "B.SilkS")
		)
		(fp_line
			(start 0.7874 -0.4064)
			(end -0.7874 -0.4064)
			(stroke
				(width 0.1524)
				(type default)
			)
			(layer "B.SilkS")
		)
		(fp_line
			(start -0.67945 0.3048)
			(end -0.120396 0.3048)
			(stroke
				(width 0.1)
				(type default)
			)
			(layer "B.Fab")
		)
		(fp_line
			(start -0.120396 0.3048)
			(end -0.120396 0.2794)
			(stroke
				(width 0.1)
				(type default)
			)
			(layer "B.Fab")
		)
		(fp_line
			(start 0.12065 0.3048)
			(end 0.67945 0.3048)
			(stroke
				(width 0.1)
				(type default)
			)
			(layer "B.Fab")
		)
		(fp_line
			(start 0.67945 0.3048)
			(end 0.67945 -0.305054)
			(stroke
				(width 0.1)
				(type default)
			)
			(layer "B.Fab")
		)
		(fp_line
			(start -0.120396 0.2794)
			(end 0.12065 0.2794)
			(stroke
				(width 0.1)
				(type default)
			)
			(layer "B.Fab")
		)
		(fp_line
			(start 0.12065 0.2794)
			(end 0.12065 0.3048)
			(stroke
				(width 0.1)
				(type default)
			)
			(layer "B.Fab")
		)
		(fp_line
			(start -0.12065 -0.2794)
			(end -0.12065 -0.3048)
			(stroke
				(width 0.1)
				(type default)
			)
			(layer "B.Fab")
		)
		(fp_line
			(start 0.12065 -0.2794)
			(end -0.12065 -0.2794)
			(stroke
				(width 0.1)
				(type default)
			)
			(layer "B.Fab")
		)
		(fp_line
			(start -0.67945 -0.3048)
			(end -0.67945 0.3048)
			(stroke
				(width 0.1)
				(type default)
			)
			(layer "B.Fab")
		)
		(fp_line
			(start -0.12065 -0.3048)
			(end -0.67945 -0.3048)
			(stroke
				(width 0.1)
				(type default)
			)
			(layer "B.Fab")
		)
		(fp_line
			(start 0.12065 -0.305054)
			(end 0.12065 -0.2794)
			(stroke
				(width 0.1)
				(type default)
			)
			(layer "B.Fab")
		)
		(fp_line
			(start 0.67945 -0.305054)
			(end 0.12065 -0.305054)
			(stroke
				(width 0.1)
				(type default)
			)
			(layer "B.Fab")
		)
		(pad "1" smd circle
			(at 0.40005 0 90)
			(size 0 0)
			(layers "B.Cu" "B.Mask" "B.Paste")
			(net "OCP_SFF_PRSNTA_R_N")
		)
		(pad "2" smd circle
			(at -0.40005 0 90)
			(size 0 0)
			(layers "B.Cu" "B.Mask" "B.Paste")
			(net "GND")
		)
	)
)
